FILE_TYPE = MULTI_PHYS_TABLE;

PART 'TUSB8042AIRGCR'

{========================================================================================}
:VALUE            | PART_TYPE | MATERIAL | PART_NUMBER    = STANDARD    | LIFECYCLE      | PART_NUMBER   | JEDEC_TYPE            | DESCRIPTION                          | MANUFTR | MANUF_PN         | RD_CMPLS_LVL | CMPLS_LVL | FROM_PJ       | CLASS | DIP_SMD | DATA                     | EE_CHECK_LIST | FP_ECN | PSL | CREATOR | STATUS | MSD | ESD_CDM | ESD_HBM | ESD_MM | PIN_LENGTH_SHORT_PIN | PIN_LENGTH_LONG_PIN | CREATEDAY  ;
{========================================================================================}
 'TUSB8042AIRGCR' | 'SMLF'    | 'IC'     | 'AL008042000'(!) = ''               | ''               | 'AL008042000' |'VQFN64_TH_0-5_9X9XC'| 'IC OTHER(64P) TUSB8042AIRGCR(VQFN)' | 'TIC'   | 'TUSB8042AIRGCR' | 'EP(V1)'     | 'EP(V1)'  | 'F0TG-KUO-JU' | 'IC'  | ''      | 'TIC_TUSB8042AIRGCR.pdf' | ''            | ''     | ''  | ''      | ''     | ''  | ''      | ''      | ''     | '0 MILS'             | '0 MILS'            | '20220518'
 'TUSB8042AIRGCR' | 'SMLF'    | 'EMPTY'  | 'AL008042000'(!) = ''               | ''               | 'AL008042000' |'VQFN64_TH_0-5_9X9XC'| 'IC OTHER(64P) TUSB8042AIRGCR(VQFN)' | 'TIC'   | 'TUSB8042AIRGCR' | 'EP(V1)'     | 'EP(V1)'  | 'F0TG-KUO-JU' | 'IC'  | ''      | 'TIC_TUSB8042AIRGCR.pdf' | ''            | ''     | ''  | ''      | ''     | ''  | ''      | ''      | ''     | '0 MILS'             | '0 MILS'            | '20220518'

END_PART

END.

